# BASEBOARD_FAB2 (Tioga Pass) — schematic netlist excerpt (pin names and nets, part order shuffled) for the footprints in the layout excerpt that follows; sources: Cadence DE-HDL packaged netlist, KiCad conversion of Wiwynn_Tioga_Pass_MB.brd

C2A6  CAP_A  47UF 4V 20% X5R  pkg 0603V  page 228 : A = PVDDQ_KLM ; B = GND
C1F17  CAP  0.22UF 16V 10% X7R  pkg 0402  page 181 : A = P3E_CPU1_PE3_MP_C_TXP<1> ; B = P3E_CPU1_PE3_MP_TXP<1>
C7C6  CAP_A  22.0UF 4V 20% X6S  pkg 0603V  page 212 : A = PVCCIO_CPU0 ; B = GND

(kicad_pcb
	(version 20260206)
	(generator "pcbnew")
	(generator_version "10.0")
	(general
		(thickness 1.6)
		(legacy_teardrops no)
	)
	(paper "A4")
	(title_block
		(title "Wiwynn_Tioga_Pass_MB.brd")
		(comment 1 "Tioga Pass / footprints 2194-2196 of 4770")
	)
	(layers
		(0 "F.Cu" signal "TOP")
		(4 "In1.Cu" signal "L2GND")
		(6 "In2.Cu" signal "L3")
		(8 "In3.Cu" signal "L4GND")
		(10 "In4.Cu" signal "L5")
		(12 "In5.Cu" signal "L6GND")
		(14 "In6.Cu" signal "L7VCC")
		(16 "In7.Cu" signal "L8VCC")
		(18 "In8.Cu" signal "L9GND")
		(20 "In9.Cu" signal "L10")
		(22 "In10.Cu" signal "L11GND")
		(24 "In11.Cu" signal "L12")
		(26 "In12.Cu" signal "L13GND")
		(2 "B.Cu" signal "BOTTOM")
		(9 "F.Adhes" user "F.Adhesive")
		(11 "B.Adhes" user "B.Adhesive")
		(13 "F.Paste" user "Package Geometry/Pastemask Top")
		(15 "B.Paste" user "Package Geometry/Pastemask Bottom")
		(5 "F.SilkS" user "Ref Des/Silkscreen Top")
		(7 "B.SilkS" user "Ref Des/Silkscreen Bottom")
		(1 "F.Mask" user "Board Geometry/Soldermask Top")
		(3 "B.Mask" user "Board Geometry/Soldermask Bottom")
		(17 "Dwgs.User" user "User.Drawings")
		(19 "Cmts.User" user "User.Comments")
		(21 "Eco1.User" user "User.Eco1")
		(23 "Eco2.User" user "User.Eco2")
		(25 "Edge.Cuts" user "Board Geometry/Outline")
		(27 "Margin" user)
		(31 "F.CrtYd" user "Package Geometry/Place Bound Top")
		(29 "B.CrtYd" user "Package Geometry/Place Bound Bottom")
		(35 "F.Fab" user "Ref Des/Assembly Top")
		(33 "B.Fab" user "Ref Des/Assembly Bottom")
	)
	(footprint ""
		(layer "F.Cu")
		(at 339.3948 -103.9368 90)
		(property "Reference" "C7C6"
			(at 0 0 90)
			(layer "F.SilkS")
			(hide yes)
			(effects
				(font
					(size 1.27 1.27)
				)
			)
		)
		(property "Value" ""
			(at 0 0 90)
			(layer "F.Fab")
			(effects
				(font
					(size 1.27 1.27)
				)
			)
		)
		(duplicate_pad_numbers_are_jumpers no)
		(fp_poly
			(pts
				(xy -0.4953 -0.2032) (xy 0.4953 -0.2032) (xy 0.4953 1.6002) (xy -0.4953 1.6002)
			)
			(stroke
				(width 0)
				(type default)
			)
			(fill no)
			(layer "F.CrtYd")
		)
		(fp_line
			(start 0.4953 -0.2032)
			(end 0.4953 1.6002)
			(stroke
				(width 0.1)
				(type default)
			)
			(layer "F.Fab")
		)
		(fp_line
			(start -0.4953 -0.2032)
			(end 0.4953 -0.2032)
			(stroke
				(width 0.1)
				(type default)
			)
			(layer "F.Fab")
		)
		(fp_line
			(start 0.4953 1.6002)
			(end -0.4953 1.6002)
			(stroke
				(width 0.1)
				(type default)
			)
			(layer "F.Fab")
		)
		(fp_line
			(start -0.4953 1.6002)
			(end -0.4953 -0.2032)
			(stroke
				(width 0.1)
				(type default)
			)
			(layer "F.Fab")
		)
		(pad "1" smd rect
			(at 0 0 90)
			(size 0.762 0.889)
			(layers "F.Cu" "F.Mask" "F.Paste")
			(net "PVCCIO_CPU0")
		)
		(pad "2" smd rect
			(at 0 1.397 90)
			(size 0.762 0.889)
			(layers "F.Cu" "F.Mask" "F.Paste")
			(net "GND")
		)
		(zone
			(layer "F.Cu")
			(hatch none 0.5)
			(connect_pads
				(clearance 0)
			)
			(min_thickness 0.25)
			(keepout
				(tracks not_allowed)
				(vias allowed)
				(pads allowed)
				(copperpour not_allowed)
				(footprints allowed)
			)
			(placement
				(enabled no)
				(sheetname "")
			)
			(fill
				(thermal_gap 0.5)
				(thermal_bridge_width 0.5)
				(island_removal_mode 0)
			)
			(polygon
				(pts
					(xy 339.8393 -103.5558) (xy 339.8393 -104.3178) (xy 340.3473 -104.3178) (xy 340.3473 -103.5558)
				)
			)
		)
	)
	(footprint ""
		(layer "F.Cu")
		(at 13.8938 -25.019 90)
		(property "Reference" "C1F17"
			(at 0 0 90)
			(layer "F.SilkS")
			(hide yes)
			(effects
				(font
					(size 1.27 1.27)
				)
			)
		)
		(property "Value" ""
			(at 0 0 90)
			(layer "F.Fab")
			(effects
				(font
					(size 1.27 1.27)
				)
			)
		)
		(duplicate_pad_numbers_are_jumpers no)
		(fp_rect
			(start -0.3048 -0.1016)
			(end 0.3048 0.9906)
			(stroke
				(width 0)
				(type default)
			)
			(fill no)
			(layer "F.CrtYd")
		)
		(fp_line
			(start 0.3048 -0.1016)
			(end -0.3048 -0.1016)
			(stroke
				(width 0.1)
				(type default)
			)
			(layer "F.Fab")
		)
		(fp_line
			(start -0.3048 -0.1016)
			(end -0.3048 0.9906)
			(stroke
				(width 0.1)
				(type default)
			)
			(layer "F.Fab")
		)
		(fp_line
			(start 0.3048 0.9906)
			(end 0.3048 -0.1016)
			(stroke
				(width 0.1)
				(type default)
			)
			(layer "F.Fab")
		)
		(fp_line
			(start -0.3048 0.9906)
			(end 0.3048 0.9906)
			(stroke
				(width 0.1)
				(type default)
			)
			(layer "F.Fab")
		)
		(pad "1" smd rect
			(at 0 0 90)
			(size 0.508 0.508)
			(layers "F.Cu" "F.Mask" "F.Paste")
			(net "P3E_CPU1_PE3_MP_C_TXP<1>")
		)
		(pad "2" smd rect
			(at 0 0.889 90)
			(size 0.508 0.508)
			(layers "F.Cu" "F.Mask" "F.Paste")
			(net "P3E_CPU1_PE3_MP_TXP<1>")
		)
		(zone
			(layer "F.Cu")
			(hatch none 0.5)
			(connect_pads
				(clearance 0)
			)
			(min_thickness 0.25)
			(keepout
				(tracks allowed)
				(vias not_allowed)
				(pads allowed)
				(copperpour not_allowed)
				(footprints allowed)
			)
			(placement
				(enabled no)
				(sheetname "")
			)
			(fill
				(thermal_gap 0.5)
				(thermal_bridge_width 0.5)
				(island_removal_mode 0)
			)
			(polygon
				(pts
					(xy 14.1478 -24.765) (xy 14.5288 -24.765) (xy 14.5288 -25.273) (xy 14.1478 -25.273)
				)
			)
		)
		(zone
			(layer "F.Cu")
			(hatch none 0.5)
			(connect_pads
				(clearance 0)
			)
			(min_thickness 0.25)
			(keepout
				(tracks not_allowed)
				(vias allowed)
				(pads allowed)
				(copperpour not_allowed)
				(footprints allowed)
			)
			(placement
				(enabled no)
				(sheetname "")
			)
			(fill
				(thermal_gap 0.5)
				(thermal_bridge_width 0.5)
				(island_removal_mode 0)
			)
			(polygon
				(pts
					(xy 14.1478 -24.765) (xy 14.5288 -24.765) (xy 14.5288 -25.273) (xy 14.1478 -25.273)
				)
			)
		)
	)
	(footprint ""
		(layer "F.Cu")
		(at 101.3968 -149.8092 90)
		(property "Reference" "C2A6"
			(at 1.848866 0.752348 90)
			(unlocked yes)
			(layer "F.SilkS")
			(effects
				(font
					(size 1.27 0.9652)
					(thickness 0.1524)
				)
			)
		)
		(property "Value" ""
			(at 0 0 90)
			(layer "F.Fab")
			(effects
				(font
					(size 1.27 1.27)
				)
			)
		)
		(duplicate_pad_numbers_are_jumpers no)
		(fp_rect
			(start -0.500126 1.598422)
			(end 0.500126 -0.201422)
			(stroke
				(width 0)
				(type default)
			)
			(fill no)
			(layer "F.CrtYd")
		)
		(fp_line
			(start 0.500126 -0.201422)
			(end 0.500126 1.598422)
			(stroke
				(width 0.1)
				(type default)
			)
			(layer "F.Fab")
		)
		(fp_line
			(start -0.500126 -0.201422)
			(end 0.500126 -0.201422)
			(stroke
				(width 0.1)
				(type default)
			)
			(layer "F.Fab")
		)
		(fp_line
			(start 0.500126 1.598422)
			(end -0.500126 1.598422)
			(stroke
				(width 0.1)
				(type default)
			)
			(layer "F.Fab")
		)
		(fp_line
			(start -0.500126 1.598422)
			(end -0.500126 -0.201422)
			(stroke
				(width 0.1)
				(type default)
			)
			(layer "F.Fab")
		)
		(pad "1" smd rect
			(at 0 0)
			(size 0.889 0.9906)
			(layers "F.Cu" "F.Mask" "F.Paste")
			(net "PVDDQ_KLM")
		)
		(pad "2" smd rect
			(at 0 1.397)
			(size 0.889 0.9906)
			(layers "F.Cu" "F.Mask" "F.Paste")
			(net "GND")
		)
		(zone
			(layer "F.Cu")
			(hatch none 0.5)
			(connect_pads
				(clearance 0)
			)
			(min_thickness 0.25)
			(keepout
				(tracks allowed)
				(vias not_allowed)
				(pads allowed)
				(copperpour not_allowed)
				(footprints allowed)
			)
			(placement
				(enabled no)
				(sheetname "")
			)
			(fill
				(thermal_gap 0.5)
				(thermal_bridge_width 0.5)
				(island_removal_mode 0)
			)
			(polygon
				(pts
					(xy 102.3493 -149.3139) (xy 102.3493 -150.3045) (xy 101.8413 -150.3045) (xy 101.8413 -149.3139)
				)
			)
		)
		(zone
			(layer "F.Cu")
			(hatch none 0.5)
			(connect_pads
				(clearance 0)
			)
			(min_thickness 0.25)
			(keepout
				(tracks not_allowed)
				(vias allowed)
				(pads allowed)
				(copperpour not_allowed)
				(footprints allowed)
			)
			(placement
				(enabled no)
				(sheetname "")
			)
			(fill
				(thermal_gap 0.5)
				(thermal_bridge_width 0.5)
				(island_removal_mode 0)
			)
			(polygon
				(pts
					(xy 102.3493 -149.3139) (xy 102.3493 -150.3045) (xy 101.8413 -150.3045) (xy 101.8413 -149.3139)
				)
			)
		)
	)
)
